(kicad_pcb
	(version 20260206)
	(generator "pcbnew")
	(generator_version "10.0")
	(general
		(thickness 1.6)
		(legacy_teardrops no)
	)
	(paper "A4")
	(title_block
		(title "Bryce Canyon_IOM_IOC_16318-2_OCP.brd")
		(comment 1 "Bryce Canyon / footprint 592 of 1605 (U1), pads 590-710 of 896")
	)
	(layers
		(0 "F.Cu" signal "TOP")
		(4 "In1.Cu" signal "L2GND")
		(6 "In2.Cu" signal "L3")
		(8 "In3.Cu" signal "L4VCC")
		(10 "In4.Cu" signal "L5VCC")
		(12 "In5.Cu" signal "L6")
		(14 "In6.Cu" signal "L7GND")
		(2 "B.Cu" signal "BOTTOM")
		(9 "F.Adhes" user "F.Adhesive")
		(11 "B.Adhes" user "B.Adhesive")
		(13 "F.Paste" user "Package Geometry/Pastemask Top")
		(15 "B.Paste" user "Package Geometry/Pastemask Bottom")
		(5 "F.SilkS" user "Ref Des/Silkscreen Top")
		(7 "B.SilkS" user "Ref Des/Silkscreen Bottom")
		(1 "F.Mask" user "Board Geometry/Soldermask Top")
		(3 "B.Mask" user "Board Geometry/Soldermask Bottom")
		(17 "Dwgs.User" user "User.Drawings")
		(19 "Cmts.User" user "User.Comments")
		(21 "Eco1.User" user "User.Eco1")
		(23 "Eco2.User" user "User.Eco2")
		(25 "Edge.Cuts" user "Board Geometry/Outline")
		(27 "Margin" user)
		(31 "F.CrtYd" user "Package Geometry/Place Bound Top")
		(29 "B.CrtYd" user "Package Geometry/Place Bound Bottom")
		(35 "F.Fab" user "Ref Des/Assembly Top")
		(33 "B.Fab" user "Ref Des/Assembly Bottom")
	)
	(footprint ""
		(layer "F.Cu")
		(at 192.79997 -65.099946 180)
		(property "Reference" "U1"
			(at 0 0 180)
			(layer "F.SilkS")
			(hide yes)
			(effects
				(font
					(size 1.27 1.27)
				)
			)
		)
		(property "Value" "SAS3008C0-1-DB-500020657-1-GP"
			(at -20.374102 -5.0292 180)
			(unlocked yes)
			(layer "F.Fab")
			(hide yes)
			(effects
				(font
					(size 1.016 1.016)
					(thickness 0.1524)
				)
			)
		)
		(property "Device Type" "BGA896D25H78"
			(at -20.374102 -6.5532 180)
			(unlocked yes)
			(layer "F.Fab")
			(hide yes)
			(effects
				(font
					(size 1.016 1.016)
					(thickness 0.1524)
				)
			)
		)
		(duplicate_pad_numbers_are_jumpers no)
		(pad "K24" smd circle
			(at 6.800088 -4.400042 180)
			(size 0.3556 0.3556)
			(layers "F.Cu" "F.Mask" "F.Paste")
			(net "GND")
		)
		(pad "K25" smd circle
			(at 7.599934 -4.400042 180)
			(size 0.3556 0.3556)
			(layers "F.Cu" "F.Mask" "F.Paste")
			(net "GND")
		)
		(pad "K26" smd circle
			(at 8.400034 -4.400042 180)
			(size 0.3556 0.3556)
			(layers "F.Cu" "F.Mask" "F.Paste")
			(net "P1V8")
		)
		(pad "K27" smd circle
			(at 9.19988 -4.400042 180)
			(size 0.3556 0.3556)
			(layers "F.Cu" "F.Mask" "F.Paste")
			(net "GND")
		)
		(pad "K28" smd circle
			(at 9.99998 -4.400042 180)
			(size 0.3556 0.3556)
			(layers "F.Cu" "F.Mask" "F.Paste")
			(net "XM_DATA_2")
		)
		(pad "K29" smd circle
			(at 10.80008 -4.400042 180)
			(size 0.3556 0.3556)
			(layers "F.Cu" "F.Mask" "F.Paste")
			(net "XM_ADDR_23")
		)
		(pad "K30" smd circle
			(at 11.599926 -4.400042 180)
			(size 0.3556 0.3556)
			(layers "F.Cu" "F.Mask" "F.Paste")
			(net "XM_DATA_1")
		)
		(pad "L1" smd circle
			(at -11.599926 -3.599942 180)
			(size 0.3556 0.3556)
			(layers "F.Cu" "F.Mask" "F.Paste")
			(net "SIO_CLK_1")
		)
		(pad "L2" smd circle
			(at -10.80008 -3.599942 180)
			(size 0.3556 0.3556)
			(layers "F.Cu" "F.Mask" "F.Paste")
			(net "SIO_DIN_1")
		)
		(pad "L3" smd circle
			(at -9.99998 -3.599942 180)
			(size 0.3556 0.3556)
			(layers "F.Cu" "F.Mask" "F.Paste")
			(net "Net_1244")
		)
		(pad "L4" smd circle
			(at -9.19988 -3.599942 180)
			(size 0.3556 0.3556)
			(layers "F.Cu" "F.Mask" "F.Paste")
			(net "GND")
		)
		(pad "L5" smd circle
			(at -8.400034 -3.599942 180)
			(size 0.3556 0.3556)
			(layers "F.Cu" "F.Mask" "F.Paste")
			(net "P1V8")
		)
		(pad "L6" smd circle
			(at -7.599934 -3.599942 180)
			(size 0.3556 0.3556)
			(layers "F.Cu" "F.Mask" "F.Paste")
			(net "ICE1_TDI")
		)
		(pad "L7" smd circle
			(at -6.800088 -3.599942 180)
			(size 0.3556 0.3556)
			(layers "F.Cu" "F.Mask" "F.Paste")
			(net "GND")
		)
		(pad "L8" smd circle
			(at -5.999988 -3.599942 180)
			(size 0.3556 0.3556)
			(layers "F.Cu" "F.Mask" "F.Paste")
			(net "GND")
		)
		(pad "L9" smd circle
			(at -5.199888 -3.599942 180)
			(size 0.3556 0.3556)
			(layers "F.Cu" "F.Mask" "F.Paste")
			(net "GND")
		)
		(pad "L10" smd circle
			(at -4.400042 -3.599942 180)
			(size 0.3556 0.3556)
			(layers "F.Cu" "F.Mask" "F.Paste")
			(net "GND")
		)
		(pad "L11" smd circle
			(at -3.599942 -3.599942 180)
			(size 0.3556 0.3556)
			(layers "F.Cu" "F.Mask" "F.Paste")
			(net "GND")
		)
		(pad "L12" smd circle
			(at -2.800096 -3.599942 180)
			(size 0.3556 0.3556)
			(layers "F.Cu" "F.Mask" "F.Paste")
			(net "GND")
		)
		(pad "L13" smd circle
			(at -1.999996 -3.599942 180)
			(size 0.3556 0.3556)
			(layers "F.Cu" "F.Mask" "F.Paste")
			(net "GND")
		)
		(pad "L14" smd circle
			(at -1.199896 -3.599942 180)
			(size 0.3556 0.3556)
			(layers "F.Cu" "F.Mask" "F.Paste")
			(net "P0V975")
		)
		(pad "L15" smd circle
			(at -0.40005 -3.599942 180)
			(size 0.3556 0.3556)
			(layers "F.Cu" "F.Mask" "F.Paste")
			(net "GND")
		)
		(pad "L16" smd circle
			(at 0.40005 -3.599942 180)
			(size 0.3556 0.3556)
			(layers "F.Cu" "F.Mask" "F.Paste")
			(net "P0V975")
		)
		(pad "L17" smd circle
			(at 1.199896 -3.599942 180)
			(size 0.3556 0.3556)
			(layers "F.Cu" "F.Mask" "F.Paste")
			(net "GND")
		)
		(pad "L18" smd circle
			(at 1.999996 -3.599942 180)
			(size 0.3556 0.3556)
			(layers "F.Cu" "F.Mask" "F.Paste")
			(net "P0V975")
		)
		(pad "L19" smd circle
			(at 2.800096 -3.599942 180)
			(size 0.3556 0.3556)
			(layers "F.Cu" "F.Mask" "F.Paste")
			(net "GND")
		)
		(pad "L20" smd circle
			(at 3.599942 -3.599942 180)
			(size 0.3556 0.3556)
			(layers "F.Cu" "F.Mask" "F.Paste")
			(net "P0V975")
		)
		(pad "L21" smd circle
			(at 4.400042 -3.599942 180)
			(size 0.3556 0.3556)
			(layers "F.Cu" "F.Mask" "F.Paste")
			(net "GND")
		)
		(pad "L22" smd circle
			(at 5.199888 -3.599942 180)
			(size 0.3556 0.3556)
			(layers "F.Cu" "F.Mask" "F.Paste")
			(net "VDDIO_15")
		)
		(pad "L23" smd circle
			(at 5.999988 -3.599942 180)
			(size 0.3556 0.3556)
			(layers "F.Cu" "F.Mask" "F.Paste")
			(net "GND")
		)
		(pad "L24" smd circle
			(at 6.800088 -3.599942 180)
			(size 0.3556 0.3556)
			(layers "F.Cu" "F.Mask" "F.Paste")
			(net "GND")
		)
		(pad "L25" smd circle
			(at 7.599934 -3.599942 180)
			(size 0.3556 0.3556)
			(layers "F.Cu" "F.Mask" "F.Paste")
			(net "GND")
		)
		(pad "L26" smd circle
			(at 8.400034 -3.599942 180)
			(size 0.3556 0.3556)
			(layers "F.Cu" "F.Mask" "F.Paste")
			(net "GND")
		)
		(pad "L27" smd circle
			(at 9.19988 -3.599942 180)
			(size 0.3556 0.3556)
			(layers "F.Cu" "F.Mask" "F.Paste")
			(net "P1V8")
		)
		(pad "L28" smd circle
			(at 9.99998 -3.599942 180)
			(size 0.3556 0.3556)
			(layers "F.Cu" "F.Mask" "F.Paste")
			(net "GND")
		)
		(pad "L29" smd circle
			(at 10.80008 -3.599942 180)
			(size 0.3556 0.3556)
			(layers "F.Cu" "F.Mask" "F.Paste")
			(net "XM_DATA_4")
		)
		(pad "L30" smd circle
			(at 11.599926 -3.599942 180)
			(size 0.3556 0.3556)
			(layers "F.Cu" "F.Mask" "F.Paste")
			(net "XM_DATA_3")
		)
		(pad "M1" smd circle
			(at -11.599926 -2.800096 180)
			(size 0.3556 0.3556)
			(layers "F.Cu" "F.Mask" "F.Paste")
			(net "SIO_CLK_0")
		)
		(pad "M2" smd circle
			(at -10.80008 -2.800096 180)
			(size 0.3556 0.3556)
			(layers "F.Cu" "F.Mask" "F.Paste")
			(net "SIO_DOUT_1")
		)
		(pad "M3" smd circle
			(at -9.99998 -2.800096 180)
			(size 0.3556 0.3556)
			(layers "F.Cu" "F.Mask" "F.Paste")
			(net "SIO_LOAD_0")
		)
		(pad "M4" smd circle
			(at -9.19988 -2.800096 180)
			(size 0.3556 0.3556)
			(layers "F.Cu" "F.Mask" "F.Paste")
			(net "P1V8")
		)
		(pad "M5" smd circle
			(at -8.400034 -2.800096 180)
			(size 0.3556 0.3556)
			(layers "F.Cu" "F.Mask" "F.Paste")
			(net "GND")
		)
		(pad "M6" smd circle
			(at -7.599934 -2.800096 180)
			(size 0.3556 0.3556)
			(layers "F.Cu" "F.Mask" "F.Paste")
			(net "ICE_SEL")
		)
		(pad "M7" smd circle
			(at -6.800088 -2.800096 180)
			(size 0.3556 0.3556)
			(layers "F.Cu" "F.Mask" "F.Paste")
			(net "GND")
		)
		(pad "M8" smd circle
			(at -5.999988 -2.800096 180)
			(size 0.3556 0.3556)
			(layers "F.Cu" "F.Mask" "F.Paste")
			(net "GND")
		)
		(pad "M9" smd circle
			(at -5.199888 -2.800096 180)
			(size 0.3556 0.3556)
			(layers "F.Cu" "F.Mask" "F.Paste")
			(net "P1V8")
		)
		(pad "M10" smd circle
			(at -4.400042 -2.800096 180)
			(size 0.3556 0.3556)
			(layers "F.Cu" "F.Mask" "F.Paste")
			(net "GND")
		)
		(pad "M11" smd circle
			(at -3.599942 -2.800096 180)
			(size 0.3556 0.3556)
			(layers "F.Cu" "F.Mask" "F.Paste")
			(net "P0V975")
		)
		(pad "M12" smd circle
			(at -2.800096 -2.800096 180)
			(size 0.3556 0.3556)
			(layers "F.Cu" "F.Mask" "F.Paste")
			(net "GND")
		)
		(pad "M13" smd circle
			(at -1.999996 -2.800096 180)
			(size 0.3556 0.3556)
			(layers "F.Cu" "F.Mask" "F.Paste")
			(net "P0V975")
		)
		(pad "M14" smd circle
			(at -1.199896 -2.800096 180)
			(size 0.3556 0.3556)
			(layers "F.Cu" "F.Mask" "F.Paste")
			(net "GND")
		)
		(pad "M15" smd circle
			(at -0.40005 -2.800096 180)
			(size 0.3556 0.3556)
			(layers "F.Cu" "F.Mask" "F.Paste")
			(net "P0V975")
		)
		(pad "M16" smd circle
			(at 0.40005 -2.800096 180)
			(size 0.3556 0.3556)
			(layers "F.Cu" "F.Mask" "F.Paste")
			(net "GND")
		)
		(pad "M17" smd circle
			(at 1.199896 -2.800096 180)
			(size 0.3556 0.3556)
			(layers "F.Cu" "F.Mask" "F.Paste")
			(net "P0V975")
		)
		(pad "M18" smd circle
			(at 1.999996 -2.800096 180)
			(size 0.3556 0.3556)
			(layers "F.Cu" "F.Mask" "F.Paste")
			(net "GND")
		)
		(pad "M19" smd circle
			(at 2.800096 -2.800096 180)
			(size 0.3556 0.3556)
			(layers "F.Cu" "F.Mask" "F.Paste")
			(net "P0V975")
		)
		(pad "M20" smd circle
			(at 3.599942 -2.800096 180)
			(size 0.3556 0.3556)
			(layers "F.Cu" "F.Mask" "F.Paste")
			(net "GND")
		)
		(pad "M21" smd circle
			(at 4.400042 -2.800096 180)
			(size 0.3556 0.3556)
			(layers "F.Cu" "F.Mask" "F.Paste")
			(net "P0V975")
		)
		(pad "M22" smd circle
			(at 5.199888 -2.800096 180)
			(size 0.3556 0.3556)
			(layers "F.Cu" "F.Mask" "F.Paste")
			(net "GND")
		)
		(pad "M23" smd circle
			(at 5.999988 -2.800096 180)
			(size 0.3556 0.3556)
			(layers "F.Cu" "F.Mask" "F.Paste")
			(net "GND")
		)
		(pad "M24" smd circle
			(at 6.800088 -2.800096 180)
			(size 0.3556 0.3556)
			(layers "F.Cu" "F.Mask" "F.Paste")
			(net "GND")
		)
		(pad "M25" smd circle
			(at 7.599934 -2.800096 180)
			(size 0.3556 0.3556)
			(layers "F.Cu" "F.Mask" "F.Paste")
			(net "GND")
		)
		(pad "M26" smd circle
			(at 8.400034 -2.800096 180)
			(size 0.3556 0.3556)
			(layers "F.Cu" "F.Mask" "F.Paste")
			(net "GND")
		)
		(pad "M27" smd circle
			(at 9.19988 -2.800096 180)
			(size 0.3556 0.3556)
			(layers "F.Cu" "F.Mask" "F.Paste")
			(net "GND")
		)
		(pad "M28" smd circle
			(at 9.99998 -2.800096 180)
			(size 0.3556 0.3556)
			(layers "F.Cu" "F.Mask" "F.Paste")
			(net "GND")
		)
		(pad "M29" smd circle
			(at 10.80008 -2.800096 180)
			(size 0.3556 0.3556)
			(layers "F.Cu" "F.Mask" "F.Paste")
			(net "GND")
		)
		(pad "M30" smd circle
			(at 11.599926 -2.800096 180)
			(size 0.3556 0.3556)
			(layers "F.Cu" "F.Mask" "F.Paste")
			(net "GND")
		)
		(pad "N1" smd circle
			(at -11.599926 -1.999996 180)
			(size 0.3556 0.3556)
			(layers "F.Cu" "F.Mask" "F.Paste")
			(net "GND")
		)
		(pad "N2" smd circle
			(at -10.80008 -1.999996 180)
			(size 0.3556 0.3556)
			(layers "F.Cu" "F.Mask" "F.Paste")
			(net "GND")
		)
		(pad "N3" smd circle
			(at -9.99998 -1.999996 180)
			(size 0.3556 0.3556)
			(layers "F.Cu" "F.Mask" "F.Paste")
			(net "P1V8")
		)
		(pad "N4" smd circle
			(at -9.19988 -1.999996 180)
			(size 0.3556 0.3556)
			(layers "F.Cu" "F.Mask" "F.Paste")
			(net "GND")
		)
		(pad "N5" smd circle
			(at -8.400034 -1.999996 180)
			(size 0.3556 0.3556)
			(layers "F.Cu" "F.Mask" "F.Paste")
			(net "Net_1245")
		)
		(pad "N6" smd circle
			(at -7.599934 -1.999996 180)
			(size 0.3556 0.3556)
			(layers "F.Cu" "F.Mask" "F.Paste")
			(net "Net_1246")
		)
		(pad "N7" smd circle
			(at -6.800088 -1.999996 180)
			(size 0.3556 0.3556)
			(layers "F.Cu" "F.Mask" "F.Paste")
			(net "GND")
		)
		(pad "N8" smd circle
			(at -5.999988 -1.999996 180)
			(size 0.3556 0.3556)
			(layers "F.Cu" "F.Mask" "F.Paste")
			(net "GND")
		)
		(pad "N9" smd circle
			(at -5.199888 -1.999996 180)
			(size 0.3556 0.3556)
			(layers "F.Cu" "F.Mask" "F.Paste")
			(net "GND")
		)
		(pad "N10" smd circle
			(at -4.400042 -1.999996 180)
			(size 0.3556 0.3556)
			(layers "F.Cu" "F.Mask" "F.Paste")
			(net "GND")
		)
		(pad "N11" smd circle
			(at -3.599942 -1.999996 180)
			(size 0.3556 0.3556)
			(layers "F.Cu" "F.Mask" "F.Paste")
			(net "GND")
		)
		(pad "N12" smd circle
			(at -2.800096 -1.999996 180)
			(size 0.3556 0.3556)
			(layers "F.Cu" "F.Mask" "F.Paste")
			(net "P0V975")
		)
		(pad "N13" smd circle
			(at -1.999996 -1.999996 180)
			(size 0.3556 0.3556)
			(layers "F.Cu" "F.Mask" "F.Paste")
			(net "GND")
		)
		(pad "N14" smd circle
			(at -1.199896 -1.999996 180)
			(size 0.3556 0.3556)
			(layers "F.Cu" "F.Mask" "F.Paste")
			(net "P0V975")
		)
		(pad "N15" smd circle
			(at -0.40005 -1.999996 180)
			(size 0.3556 0.3556)
			(layers "F.Cu" "F.Mask" "F.Paste")
			(net "GND")
		)
		(pad "N16" smd circle
			(at 0.40005 -1.999996 180)
			(size 0.3556 0.3556)
			(layers "F.Cu" "F.Mask" "F.Paste")
			(net "P0V975")
		)
		(pad "N17" smd circle
			(at 1.199896 -1.999996 180)
			(size 0.3556 0.3556)
			(layers "F.Cu" "F.Mask" "F.Paste")
			(net "GND")
		)
		(pad "N18" smd circle
			(at 1.999996 -1.999996 180)
			(size 0.3556 0.3556)
			(layers "F.Cu" "F.Mask" "F.Paste")
			(net "P0V975")
		)
		(pad "N19" smd circle
			(at 2.800096 -1.999996 180)
			(size 0.3556 0.3556)
			(layers "F.Cu" "F.Mask" "F.Paste")
			(net "GND")
		)
		(pad "N20" smd circle
			(at 3.599942 -1.999996 180)
			(size 0.3556 0.3556)
			(layers "F.Cu" "F.Mask" "F.Paste")
			(net "P0V975")
		)
		(pad "N21" smd circle
			(at 4.400042 -1.999996 180)
			(size 0.3556 0.3556)
			(layers "F.Cu" "F.Mask" "F.Paste")
			(net "GND")
		)
		(pad "N22" smd circle
			(at 5.199888 -1.999996 180)
			(size 0.3556 0.3556)
			(layers "F.Cu" "F.Mask" "F.Paste")
			(net "GND")
		)
		(pad "N23" smd circle
			(at 5.999988 -1.999996 180)
			(size 0.3556 0.3556)
			(layers "F.Cu" "F.Mask" "F.Paste")
			(net "GND")
		)
		(pad "N24" smd circle
			(at 6.800088 -1.999996 180)
			(size 0.3556 0.3556)
			(layers "F.Cu" "F.Mask" "F.Paste")
			(net "GND")
		)
		(pad "N25" smd circle
			(at 7.599934 -1.999996 180)
			(size 0.3556 0.3556)
			(layers "F.Cu" "F.Mask" "F.Paste")
			(net "GND")
		)
		(pad "N26" smd circle
			(at 8.400034 -1.999996 180)
			(size 0.3556 0.3556)
			(layers "F.Cu" "F.Mask" "F.Paste")
			(net "GND")
		)
		(pad "N27" smd circle
			(at 9.19988 -1.999996 180)
			(size 0.3556 0.3556)
			(layers "F.Cu" "F.Mask" "F.Paste")
			(net "P1V8")
		)
		(pad "N28" smd circle
			(at 9.99998 -1.999996 180)
			(size 0.3556 0.3556)
			(layers "F.Cu" "F.Mask" "F.Paste")
			(net "IOC_GPIO_32")
		)
		(pad "N29" smd circle
			(at 10.80008 -1.999996 180)
			(size 0.3556 0.3556)
			(layers "F.Cu" "F.Mask" "F.Paste")
			(net "MEM_CLK_SEL")
		)
		(pad "N30" smd circle
			(at 11.599926 -1.999996 180)
			(size 0.3556 0.3556)
			(layers "F.Cu" "F.Mask" "F.Paste")
			(net "SBL_SDA")
		)
		(pad "P1" smd circle
			(at -11.599926 -1.199896 180)
			(size 0.3556 0.3556)
			(layers "F.Cu" "F.Mask" "F.Paste")
			(net "IOC_REF_CLK_P")
		)
		(pad "P2" smd circle
			(at -10.80008 -1.199896 180)
			(size 0.3556 0.3556)
			(layers "F.Cu" "F.Mask" "F.Paste")
			(net "IOC_REF_CLK_N")
		)
		(pad "P3" smd circle
			(at -9.99998 -1.199896 180)
			(size 0.3556 0.3556)
			(layers "F.Cu" "F.Mask" "F.Paste")
			(net "GND")
		)
		(pad "P4" smd circle
			(at -9.19988 -1.199896 180)
			(size 0.3556 0.3556)
			(layers "F.Cu" "F.Mask" "F.Paste")
			(net "P1V8")
		)
		(pad "P5" smd circle
			(at -8.400034 -1.199896 180)
			(size 0.3556 0.3556)
			(layers "F.Cu" "F.Mask" "F.Paste")
			(net "Net_1247")
		)
		(pad "P6" smd circle
			(at -7.599934 -1.199896 180)
			(size 0.3556 0.3556)
			(layers "F.Cu" "F.Mask" "F.Paste")
			(net "Net_1248")
		)
		(pad "P7" smd circle
			(at -6.800088 -1.199896 180)
			(size 0.3556 0.3556)
			(layers "F.Cu" "F.Mask" "F.Paste")
			(net "GND")
		)
		(pad "P8" smd circle
			(at -5.999988 -1.199896 180)
			(size 0.3556 0.3556)
			(layers "F.Cu" "F.Mask" "F.Paste")
			(net "GND")
		)
		(pad "P9" smd circle
			(at -5.199888 -1.199896 180)
			(size 0.3556 0.3556)
			(layers "F.Cu" "F.Mask" "F.Paste")
			(net "GND")
		)
		(pad "P10" smd circle
			(at -4.400042 -1.199896 180)
			(size 0.3556 0.3556)
			(layers "F.Cu" "F.Mask" "F.Paste")
			(net "GND")
		)
		(pad "P11" smd circle
			(at -3.599942 -1.199896 180)
			(size 0.3556 0.3556)
			(layers "F.Cu" "F.Mask" "F.Paste")
			(net "GND")
		)
		(pad "P12" smd circle
			(at -2.800096 -1.199896 180)
			(size 0.3556 0.3556)
			(layers "F.Cu" "F.Mask" "F.Paste")
			(net "GND")
		)
		(pad "P13" smd circle
			(at -1.999996 -1.199896 180)
			(size 0.3556 0.3556)
			(layers "F.Cu" "F.Mask" "F.Paste")
			(net "P0V975")
		)
		(pad "P14" smd circle
			(at -1.199896 -1.199896 180)
			(size 0.3556 0.3556)
			(layers "F.Cu" "F.Mask" "F.Paste")
			(net "GND")
		)
		(pad "P15" smd circle
			(at -0.40005 -1.199896 180)
			(size 0.3556 0.3556)
			(layers "F.Cu" "F.Mask" "F.Paste")
			(net "P0V975")
		)
		(pad "P16" smd circle
			(at 0.40005 -1.199896 180)
			(size 0.3556 0.3556)
			(layers "F.Cu" "F.Mask" "F.Paste")
			(net "GND")
		)
		(pad "P17" smd circle
			(at 1.199896 -1.199896 180)
			(size 0.3556 0.3556)
			(layers "F.Cu" "F.Mask" "F.Paste")
			(net "P0V975")
		)
		(pad "P18" smd circle
			(at 1.999996 -1.199896 180)
			(size 0.3556 0.3556)
			(layers "F.Cu" "F.Mask" "F.Paste")
			(net "GND")
		)
		(pad "P19" smd circle
			(at 2.800096 -1.199896 180)
			(size 0.3556 0.3556)
			(layers "F.Cu" "F.Mask" "F.Paste")
			(net "P0V975")
		)
		(pad "P20" smd circle
			(at 3.599942 -1.199896 180)
			(size 0.3556 0.3556)
			(layers "F.Cu" "F.Mask" "F.Paste")
			(net "GND")
		)
		(pad "P21" smd circle
			(at 4.400042 -1.199896 180)
			(size 0.3556 0.3556)
			(layers "F.Cu" "F.Mask" "F.Paste")
			(net "P0V975")
		)
		(pad "P22" smd circle
			(at 5.199888 -1.199896 180)
			(size 0.3556 0.3556)
			(layers "F.Cu" "F.Mask" "F.Paste")
			(net "GND")
		)
		(pad "P23" smd circle
			(at 5.999988 -1.199896 180)
			(size 0.3556 0.3556)
			(layers "F.Cu" "F.Mask" "F.Paste")
			(net "GND")
		)
		(pad "P24" smd circle
			(at 6.800088 -1.199896 180)
			(size 0.3556 0.3556)
			(layers "F.Cu" "F.Mask" "F.Paste")
			(net "GND")
		)
	)
)
